# S9S_MB_2U (Grand Teton) — schematic netlist excerpt (pin names and nets, part order shuffled) for the footprints in the layout excerpt that follows; sources: Cadence DE-HDL packaged netlist, KiCad conversion of 03242023_DA0F0TMBIJ0_F0T_Motherboard_J_brd_V01_OCP.brd

PC1576  Q_CAPP  560UF 2.5V 20% OSCON  pkg THLF  page 275 : A = PVCCINFAON_CPU0 ; B = GND
R4498  Q_RES  4.7K 5% CHIP  pkg 0402LF  page 237 : A = P3V3 ; B = SMB_HOST_CLK_BUF_ISO_3V3AUX_S_1
R2309  Q_RES  1K 1% CHIP  pkg 0402LF  page 236 : A = PCA9543_S3M_ADDR1 ; B = GND

(kicad_pcb
	(version 20260206)
	(generator "pcbnew")
	(generator_version "10.0")
	(general
		(thickness 1.6)
		(legacy_teardrops no)
	)
	(paper "A4")
	(title_block
		(title "03242023_DA0F0TMBIJ0_F0T_Motherboard_J_brd_V01_OCP.brd")
		(comment 1 "Grand Teton / footprints 1611-1613 of 6105")
	)
	(layers
		(0 "F.Cu" signal "TOP")
		(4 "In1.Cu" signal "GND")
		(6 "In2.Cu" signal "IN1")
		(8 "In3.Cu" signal "GND1")
		(10 "In4.Cu" signal "IN2")
		(12 "In5.Cu" signal "GND2")
		(14 "In6.Cu" signal "IN3")
		(16 "In7.Cu" signal "GND3")
		(18 "In8.Cu" signal "VCC")
		(20 "In9.Cu" signal "VCC1")
		(22 "In10.Cu" signal "GND4")
		(24 "In11.Cu" signal "IN4")
		(26 "In12.Cu" signal "GND5")
		(28 "In13.Cu" signal "IN5")
		(30 "In14.Cu" signal "GND6")
		(32 "In15.Cu" signal "IN6")
		(34 "In16.Cu" signal "GND7")
		(2 "B.Cu" signal "BOTTOM")
		(9 "F.Adhes" user "F.Adhesive")
		(11 "B.Adhes" user "B.Adhesive")
		(13 "F.Paste" user "Package Geometry/Pastemask Top")
		(15 "B.Paste" user "Package Geometry/Pastemask Bottom")
		(5 "F.SilkS" user "Ref Des/Silkscreen Top")
		(7 "B.SilkS" user "Ref Des/Silkscreen Bottom")
		(1 "F.Mask" user "Board Geometry/Soldermask Top")
		(3 "B.Mask" user "Board Geometry/Soldermask Bottom")
		(17 "Dwgs.User" user "User.Drawings")
		(19 "Cmts.User" user "User.Comments")
		(21 "Eco1.User" user "User.Eco1")
		(23 "Eco2.User" user "User.Eco2")
		(25 "Edge.Cuts" user "Board Geometry/Outline")
		(27 "Margin" user)
		(31 "F.CrtYd" user "Package Geometry/Place Bound Top")
		(29 "B.CrtYd" user "Package Geometry/Place Bound Bottom")
		(35 "F.Fab" user "Ref Des/Assembly Top")
		(33 "B.Fab" user "Ref Des/Assembly Bottom")
	)
	(footprint ""
		(layer "F.Cu")
		(at 400.558 -170.983148)
		(property "Reference" "PC1576"
			(at 0 0 0)
			(layer "F.SilkS")
			(hide yes)
			(effects
				(font
					(size 1.27 1.27)
				)
			)
		)
		(property "Value" ""
			(at 0 0 0)
			(layer "F.Fab")
			(effects
				(font
					(size 1.27 1.27)
				)
			)
		)
		(duplicate_pad_numbers_are_jumpers no)
		(fp_line
			(start 2.750058 0.999998)
			(end -2.750058 0.999998)
			(stroke
				(width 0.1524)
				(type default)
			)
			(layer "F.SilkS")
		)
		(fp_circle
			(center 0 0.999998)
			(end 2.750058 0.999998)
			(stroke
				(width 0.1524)
				(type default)
			)
			(fill no)
			(layer "F.SilkS")
		)
		(fp_poly
			(pts
				(arc
					(start 2.750058 0.999998)
					(mid 0 3.750056)
					(end -2.750058 0.999998)
				)
			)
			(stroke
				(width 0)
				(type default)
			)
			(fill yes)
			(layer "F.SilkS")
		)
		(fp_circle
			(center 0 0.999998)
			(end 2.750058 0.999998)
			(stroke
				(width 0.1)
				(type default)
			)
			(fill no)
			(layer "F.Fab")
		)
		(pad "1" thru_hole rect
			(at 0 0)
			(size 1.5748 1.5748)
			(drill 1.0668)
			(layers "*.Cu" "*.Mask")
			(remove_unused_layers no)
			(net "PVCCINFAON_CPU0")
			(clearance 0)
			(padstack
				(mode front_inner_back)
				(layer "Inner"
					(shape circle)
					(size 1.5748 1.5748)
					(clearance 0)
				)
				(layer "B.Cu"
					(shape rect)
					(size 1.5748 1.5748)
					(clearance 0)
				)
			)
		)
		(pad "2" thru_hole circle
			(at 0 1.999996)
			(size 1.5748 1.5748)
			(drill 1.0668)
			(layers "*.Cu" "*.Mask")
			(remove_unused_layers no)
			(net "GND")
			(clearance 0)
		)
	)
	(footprint ""
		(layer "F.Cu")
		(at 259.021326 -130.193796)
		(property "Reference" "R4498"
			(at 0 0 0)
			(layer "F.SilkS")
			(hide yes)
			(effects
				(font
					(size 1.27 1.27)
				)
			)
		)
		(property "Value" ""
			(at 0 0 0)
			(layer "F.Fab")
			(effects
				(font
					(size 1.27 1.27)
				)
			)
		)
		(duplicate_pad_numbers_are_jumpers no)
		(fp_line
			(start -0.7874 -0.4064)
			(end 0.7874 -0.4064)
			(stroke
				(width 0.1524)
				(type default)
			)
			(layer "F.SilkS")
		)
		(fp_line
			(start -0.7874 0.4064)
			(end -0.7874 -0.4064)
			(stroke
				(width 0.1524)
				(type default)
			)
			(layer "F.SilkS")
		)
		(fp_line
			(start 0.7874 -0.4064)
			(end 0.7874 0.4064)
			(stroke
				(width 0.1524)
				(type default)
			)
			(layer "F.SilkS")
		)
		(fp_line
			(start 0.7874 0.4064)
			(end -0.7874 0.4064)
			(stroke
				(width 0.1524)
				(type default)
			)
			(layer "F.SilkS")
		)
		(fp_line
			(start -0.67945 -0.305054)
			(end -0.12065 -0.305054)
			(stroke
				(width 0.1)
				(type default)
			)
			(layer "F.Fab")
		)
		(fp_line
			(start -0.67945 0.3048)
			(end -0.67945 -0.305054)
			(stroke
				(width 0.1)
				(type default)
			)
			(layer "F.Fab")
		)
		(fp_line
			(start -0.12065 -0.305054)
			(end -0.12065 -0.2794)
			(stroke
				(width 0.1)
				(type default)
			)
			(layer "F.Fab")
		)
		(fp_line
			(start -0.12065 -0.2794)
			(end 0.12065 -0.2794)
			(stroke
				(width 0.1)
				(type default)
			)
			(layer "F.Fab")
		)
		(fp_line
			(start -0.12065 0.2794)
			(end -0.12065 0.3048)
			(stroke
				(width 0.1)
				(type default)
			)
			(layer "F.Fab")
		)
		(fp_line
			(start -0.12065 0.3048)
			(end -0.67945 0.3048)
			(stroke
				(width 0.1)
				(type default)
			)
			(layer "F.Fab")
		)
		(fp_line
			(start 0.120396 0.2794)
			(end -0.12065 0.2794)
			(stroke
				(width 0.1)
				(type default)
			)
			(layer "F.Fab")
		)
		(fp_line
			(start 0.120396 0.3048)
			(end 0.120396 0.2794)
			(stroke
				(width 0.1)
				(type default)
			)
			(layer "F.Fab")
		)
		(fp_line
			(start 0.12065 -0.3048)
			(end 0.67945 -0.3048)
			(stroke
				(width 0.1)
				(type default)
			)
			(layer "F.Fab")
		)
		(fp_line
			(start 0.12065 -0.2794)
			(end 0.12065 -0.3048)
			(stroke
				(width 0.1)
				(type default)
			)
			(layer "F.Fab")
		)
		(fp_line
			(start 0.67945 -0.3048)
			(end 0.67945 0.3048)
			(stroke
				(width 0.1)
				(type default)
			)
			(layer "F.Fab")
		)
		(fp_line
			(start 0.67945 0.3048)
			(end 0.120396 0.3048)
			(stroke
				(width 0.1)
				(type default)
			)
			(layer "F.Fab")
		)
		(pad "1" smd circle
			(at -0.40005 0)
			(size 0 0)
			(layers "F.Cu" "F.Mask" "F.Paste")
			(net "P3V3")
		)
		(pad "2" smd circle
			(at 0.40005 0)
			(size 0 0)
			(layers "F.Cu" "F.Mask" "F.Paste")
			(net "SMB_HOST_CLK_BUF_ISO_3V3AUX_S_1")
		)
	)
	(footprint ""
		(layer "F.Cu")
		(at 153.60015 -70.26402 -90)
		(property "Reference" "R2309"
			(at 0 0 270)
			(layer "F.SilkS")
			(hide yes)
			(effects
				(font
					(size 1.27 1.27)
				)
			)
		)
		(property "Value" ""
			(at 0 0 270)
			(layer "F.Fab")
			(effects
				(font
					(size 1.27 1.27)
				)
			)
		)
		(duplicate_pad_numbers_are_jumpers no)
		(fp_line
			(start -0.7874 0.4064)
			(end -0.7874 -0.4064)
			(stroke
				(width 0.1524)
				(type default)
			)
			(layer "F.SilkS")
		)
		(fp_line
			(start 0.7874 0.4064)
			(end -0.7874 0.4064)
			(stroke
				(width 0.1524)
				(type default)
			)
			(layer "F.SilkS")
		)
		(fp_line
			(start -0.7874 -0.4064)
			(end 0.7874 -0.4064)
			(stroke
				(width 0.1524)
				(type default)
			)
			(layer "F.SilkS")
		)
		(fp_line
			(start 0.7874 -0.4064)
			(end 0.7874 0.4064)
			(stroke
				(width 0.1524)
				(type default)
			)
			(layer "F.SilkS")
		)
		(fp_line
			(start -0.67945 0.3048)
			(end -0.67945 -0.305054)
			(stroke
				(width 0.1)
				(type default)
			)
			(layer "F.Fab")
		)
		(fp_line
			(start -0.12065 0.3048)
			(end -0.67945 0.3048)
			(stroke
				(width 0.1)
				(type default)
			)
			(layer "F.Fab")
		)
		(fp_line
			(start 0.120396 0.3048)
			(end 0.120396 0.2794)
			(stroke
				(width 0.1)
				(type default)
			)
			(layer "F.Fab")
		)
		(fp_line
			(start 0.67945 0.3048)
			(end 0.120396 0.3048)
			(stroke
				(width 0.1)
				(type default)
			)
			(layer "F.Fab")
		)
		(fp_line
			(start -0.12065 0.2794)
			(end -0.12065 0.3048)
			(stroke
				(width 0.1)
				(type default)
			)
			(layer "F.Fab")
		)
		(fp_line
			(start 0.120396 0.2794)
			(end -0.12065 0.2794)
			(stroke
				(width 0.1)
				(type default)
			)
			(layer "F.Fab")
		)
		(fp_line
			(start -0.12065 -0.2794)
			(end 0.12065 -0.2794)
			(stroke
				(width 0.1)
				(type default)
			)
			(layer "F.Fab")
		)
		(fp_line
			(start 0.12065 -0.2794)
			(end 0.12065 -0.3048)
			(stroke
				(width 0.1)
				(type default)
			)
			(layer "F.Fab")
		)
		(fp_line
			(start 0.12065 -0.3048)
			(end 0.67945 -0.3048)
			(stroke
				(width 0.1)
				(type default)
			)
			(layer "F.Fab")
		)
		(fp_line
			(start 0.67945 -0.3048)
			(end 0.67945 0.3048)
			(stroke
				(width 0.1)
				(type default)
			)
			(layer "F.Fab")
		)
		(fp_line
			(start -0.67945 -0.305054)
			(end -0.12065 -0.305054)
			(stroke
				(width 0.1)
				(type default)
			)
			(layer "F.Fab")
		)
		(fp_line
			(start -0.12065 -0.305054)
			(end -0.12065 -0.2794)
			(stroke
				(width 0.1)
				(type default)
			)
			(layer "F.Fab")
		)
		(pad "1" smd circle
			(at -0.40005 0 270)
			(size 0 0)
			(layers "F.Cu" "F.Mask" "F.Paste")
			(net "PCA9543_S3M_ADDR1")
		)
		(pad "2" smd circle
			(at 0.40005 0 270)
			(size 0 0)
			(layers "F.Cu" "F.Mask" "F.Paste")
			(net "GND")
		)
	)
)
